FILE_TYPE = MACRO_DRAWING;
SET COLOR_WIRE YELLOW;
SET COLOR_PROP ORANGE;
SET COLOR_DOT WHITE;
SET COLOR_ARC YELLOW;
SET COLOR_BODY GREEN;
SET COLOR_NOTE PURPLE;
SET PROP_DISPLAY VALUE;
SET PAGE_NUMBER P145;
FORCEADD QUANTA_TITLE_BLOCK_C..1
(-3100 25);
FORCEPROP 1 LAST CUSTOM_TXT_CDS <NAME_2>
J 0
(-6275 75);
FORCEPROP 1 LAST CUSTOM_TXT_CDS <NAME_1>
J 0
(-6275 200);
FORCEPROP 1 LAST CUSTOM_TXT_CDS <Q_NUMBER>
J 0
(-4503 128);
DISPLAY 1.212766 (-4503 128);
FORCEPROP 1 LAST CUSTOM_TXT_CDS <Q_PROJ>
J 0
(-5482 127);
DISPLAY 1.212766 (-5482 127);
FORCEPROP 1 LAST CUSTOM_TXT_CDS <Q_REV>
J 0
(-3284 128);
DISPLAY 1.212766 (-3284 128);
FORCEPROP 1 LAST CUSTOM_TXT_CDS <CON_LAST_MODIFIED>
J 0
(-4985 40);
DISPLAY 0.978723 (-4985 40);
FORCEPROP 1 LAST CUSTOM_TXT_CDS <CON_PAGE_NUM> OF <CON_TOTAL_PAGES>
J 0
(-3546 43);
DISPLAY 0.978723 (-3546 43);
FORCEPROP 1 LAST Q_TITLE USB INTERNAL CONN
J 0
(-12375 100);
DISPLAY 2.446809 (-12375 100);
PAINT GREEN (-12375 100);
FORCEPROP 1 LAST Q_DEPT BU9
J 1
(-6863 74);
DISPLAY 1.957447 (-6863 74);
PAINT GREEN (-6863 74);
FORCEPROP 2 LAST PAGE_BORDER TRUE
J 0
(-10990 5275);
DISPLAY 0.638298 (-10990 5275);
PAINT PINK (-10990 5275);
DISPLAY INVISIBLE (-10990 5275);
FORCEPROP 1 LAST CDS_LMAN_SYM_OUTLINE -9475,6775,100,-125
J 0
(-3100 25);
DISPLAY 0.468085 (-3100 25);
PAINT GREEN (-3100 25);
DISPLAY INVISIBLE (-3100 25);
FORCEPROP 2 LAST CDS_LIB pure_quanta
J 0
(-3100 25);
DISPLAY INVISIBLE (-3100 25);
FORCEPROP 1 LAST COMMENT_BODY TRUE
J 0
(-3088 12);
DISPLAY 0.978723 (-3088 12);
PAINT GREEN (-3088 12);
DISPLAY INVISIBLE (-3088 12);
FORCEPROP 2 LAST CDS_XR_PAGE_TITLE CR-145 : @T6G_MB_LIB.T6G(SCH_1):PAGE145
J 0
(-10990 5275);
DISPLAY 0.638298 (-10990 5275);
PAINT PINK (-10990 5275);
DISPLAY INVISIBLE (-10990 5275);
FORCEPROP 2 LAST CUSTOM_TXT_CDS <XR_PAGE_TITLE>
J 0
(-10990 5275);
DISPLAY 0.638298 (-10990 5275);
PAINT PINK (-10990 5275);
DISPLAY INVISIBLE (-10990 5275);
FORCEPROP 0 LAST CDS_CON_LAST_MODIFIED Wed Mar 09 20:11:11 2022
J 0
(-4985 40);
DISPLAY INVISIBLE (-4985 40);
QUIT
